FILE_TYPE = CONNECTIVITY;
{Allegro Design Entry HDL 17.4-2019 S026 (4007227) 1/17/2022}
"PAGE_NUMBER" = 176;
0"NC";
1"GND\g";
2"GND\g";
3"GND\g";
4"GND\g";
5"P5V_AUX\g";
6"GND\g";
7"P3V3_AUX\g";
8"GND\g";
9"GND\g";
10"GND\g";
11"GND\g";
12"GND\g";
13"P12V_AUX\g";
14"GND\g";
15"SW_PVDDCR_CPU1_P0_BOOTR1";
16"SW_PVDDCR_CPU1_P0_BOOT1_R";
17"GND\g";
18"GND\g";
19"SW_P12V_AUX_PVDDCR_CPU1_P0_FLT\g";
20"PVDDCR_CPU1_P0_VOS1";
21"SW_PVDDCR_CPU1_P0_SW1";
22"SW_P12V_AUX_PVDDCR_CPU1_P0_FLT\g";
23"SW_PVDDCR_CPU1_P0_BOOT1";
24"SW_PVDDCR_CPU1_P0_BOOT2";
25"SW_PVDDCR_CPU1_P0_BOOT2_R";
26"NC_PVDDCR_CPU1_P0_GL1_1";
27"PVDDCR_CPU1_P0_LSET1";
28"PVDDCR_CPU1_P0_TEMP0";
29"PVDDCR_CPU1_P0_PVCC\g";
30"PVDDCR_CPU1_P0_PVCC\g";
31"GND\g";
32"GND\g";
33"GND\g";
34"PVDDCR_CPU1_P0\g";
35"GND\g";
36"PVDDCR_CPU1_P0\g";
37"GND\g";
38"PVDDCR_CPU1_P0\g";
39"PVDDCR_CPU1_P0_LSET2";
40"PVDDCR_CPU1_P0_VCCS"CDS_PHYS_NET_NAME"PVDDCR_CPU1_P0_VCCS";
41"PVDDCR_CPU1_P0_IMON2";
42"PVDDCR_CPU1_P0_VCCS"CDS_PHYS_NET_NAME"PVDDCR_CPU1_P0_VCCS";
43"PVDDCR_CPU1_P0_PWM2";
44"PVDDCR_CPU1_P0_TEMP0";
45"PVDDCR_CPU1_P0_IMON1";
46"PVDDCR_CPU1_P0_PWM1";
47"NC_PVDDCR_CPU1_P0_DNC2";
48"PVDDCR_CPU1_P0_VCC2";
49"SW_PVDDCR_CPU1_P0_BOOTR2";
50"NC_PVDDCR_CPU1_P0_GL1_2";
51"NC_PVDDCR_CPU1_P0_GL2_2";
52"PVDDCR_CPU1_P0_VOS2";
53"SW_PVDDCR_CPU1_P0_SW2_RC";
54"IND_CPU1_P0_CPL1";
55"SW_PVDDCR_CPU1_P0_SW1_RC";
56"NC_PVDDCR_CPU1_P0_DNC1";
57"PVDDCR_CPU1_P0_VCC1";
58"NC_PVDDCR_CPU1_P0_GL2_1";
59"IND_CPU1_P0_CPL5";
60"IND_CPU1_P0_CPL2";
61"IND_CPU1_P0_CPL1";
62"SW_PVDDCR_CPU1_P0_SW2";
%"UNIVERSAL_GND"
"1","(-9750,575)","0","pure_quanta_power","I1";
;
CDS_LIB"pure_quanta_power"
HDL_POWER"GND";
"A"1;
%"Q_CAP"
"1","(-8875,1600)","0","pure_quanta","I10";
;
LOCATION"PC80"
$SEC"1"
CDS_SEC"1"
PACK_TYPE"C0402"
VOLTAGE"10V"
VALUE"2.2UF"
TOLERANCE"10%"
MATERIAL"X6S"
CDS_LIB"pure_quanta"
PART_NUMBER"CH5222KEB01";
"B"
$PN"2"14;
"A"
$PN"1"48;
%"UNIVERSAL_GND"
"1","(-9625,3550)","0","pure_quanta_power","I11";
;
CDS_LIB"pure_quanta_power"
HDL_POWER"GND";
"A"2;
%"Q_CAP"
"1","(-9625,3750)","0","pure_quanta","I12";
;
LOCATION"PC84_1"
$SEC"1"
CDS_SEC"1"
PACK_TYPE"0402"
VOLTAGE"25V"
VALUE"0.1UF"
TOLERANCE"10%"
MATERIAL"X7R"
CDS_LIB"pure_quanta"
PART_NUMBER"CH4104K1B00";
"B"
$PN"2"2;
"A"
$PN"1"40;
%"Q_RES"
"2","(-8875,2150)","0","pure_quanta","I13";
;
LOCATION"PR80"
$SEC"1"
CDS_SEC"1"
MATERIAL"CHIP"
TOLERANCE"1%"
VALUE"2.2"
PACK_TYPE"0402LF"
WATTAGE"1/16W"
CDS_LIB"pure_quanta"
PART_NUMBER"CS-2202FB01";
"A"
$PN"1"29;
"B"
$PN"2"48;
%"UNIVERSAL_GND"
"1","(-8525,1900)","0","pure_quanta_power","I14";
;
CDS_LIB"pure_quanta_power"
HDL_POWER"GND";
"A"3;
%"Q_CAP"
"1","(-8525,2175)","0","pure_quanta","I15";
;
LOCATION"PC82_C1P0_2"
$SEC"1"
CDS_SEC"1"
PACK_TYPE"C0402"
VOLTAGE"10V"
TOLERANCE"10%"
MATERIAL"X6S"
VALUE"2.2UF"
CDS_LIB"pure_quanta"
PART_NUMBER"CH5222KEB01";
"B"
$PN"2"3;
"A"
$PN"1"29;
%"VCC_CORE"
"1","(-8875,2575)","0","pure_quanta_power","I16";
;
HDL_POWER"PVDDCR_CPU1_P0_PVCC"
CDS_LIB"pure_quanta_power";
"A"29;
%"UNIVERSAL_GND"
"1","(-9125,3400)","0","pure_quanta_power","I17";
;
CDS_LIB"pure_quanta_power"
HDL_POWER"GND";
"A"4;
%"Q_RES"
"2","(-9125,3625)","2","pure_quanta","I18";
;
LOCATION"PR78"
$SEC"1"
CDS_SEC"1"
WATTAGE"1/16W"
MATERIAL"EMPTY"
TOLERANCE"1%"
VALUE"8.87K"
PACK_TYPE"0402LF"
CDS_LIB"pure_quanta"
PART_NUMBER"CS28872FB01";
"A"
$PN"1"27;
"B"
$PN"2"4;
%"Q_CAP"
"1","(-9750,850)","0","pure_quanta","I2";
;
LOCATION"PC83_2"
$SEC"1"
CDS_SEC"1"
PACK_TYPE"0402"
VOLTAGE"25V"
VALUE"0.1UF"
TOLERANCE"10%"
MATERIAL"X7R"
CDS_LIB"pure_quanta"
PART_NUMBER"CH4104K1B00";
"B"
$PN"2"1;
"A"
$PN"1"42;
%"Q_RES"
"1","(-9625,5450)","1","pure_quanta","I21";
;
LOCATION"PR442"
$SEC"1"
CDS_SEC"1"
WATTAGE"1/16W"
MATERIAL"CHIP"
TOLERANCE"5%"
VALUE"0"
PACK_TYPE"0402LF"
CDS_LIB"pure_quanta"
PART_NUMBER"CS00002JB13";
"B"
$PN"2"5;
"A"
$PN"1"30;
%"VCC_CORE"
"1","(-9625,5650)","0","pure_quanta_power","I22";
;
HDL_POWER"P5V_AUX"
CDS_LIB"pure_quanta_power";
"A"5;
%"UNIVERSAL_GND"
"1","(-8975,4375)","0","pure_quanta_power","I23";
;
CDS_LIB"pure_quanta_power"
HDL_POWER"GND";
"A"6;
%"Q_CAP"
"1","(-8975,4575)","0","pure_quanta","I24";
;
LOCATION"PC79"
$SEC"1"
CDS_SEC"1"
PACK_TYPE"C0402"
VOLTAGE"10V"
VALUE"2.2UF"
TOLERANCE"10%"
MATERIAL"X6S"
CDS_LIB"pure_quanta"
PART_NUMBER"CH5222KEB01";
"B"
$PN"2"6;
"A"
$PN"1"57;
%"Q_RES"
"1","(-9275,5450)","1","pure_quanta","I27";
;
LOCATION"PR443"
$SEC"1"
CDS_SEC"1"
WATTAGE"1/16W"
MATERIAL"EMPTY"
TOLERANCE"5%"
VALUE"0"
PACK_TYPE"0402LF"
CDS_LIB"pure_quanta"
PART_NUMBER"CS00002JB13";
"B"
$PN"2"7;
"A"
$PN"1"30;
%"VCC_CORE"
"1","(-9275,5650)","0","pure_quanta_power","I28";
;
HDL_POWER"P3V3_AUX"
CDS_LIB"pure_quanta_power";
"A"7;
%"Q_RES"
"2","(-8975,5050)","0","pure_quanta","I29";
;
LOCATION"PR79"
$SEC"1"
CDS_SEC"1"
WATTAGE"1/16W"
MATERIAL"CHIP"
TOLERANCE"1%"
VALUE"2.2"
PACK_TYPE"0402LF"
CDS_LIB"pure_quanta"
PART_NUMBER"CS-2202FB01";
"A"
$PN"1"30;
"B"
$PN"2"57;
%"UNIVERSAL_GND"
"1","(-9150,450)","0","pure_quanta_power","I3";
;
CDS_LIB"pure_quanta_power"
HDL_POWER"GND";
"A"8;
%"Q_CAP"
"1","(-8625,5075)","0","pure_quanta","I30";
;
LOCATION"PC81_C1P0_1"
$SEC"1"
CDS_SEC"1"
PACK_TYPE"C0402"
VOLTAGE"10V"
VALUE"2.2UF"
TOLERANCE"10%"
MATERIAL"X6S"
CDS_LIB"pure_quanta"
PART_NUMBER"CH5222KEB01";
"B"
$PN"2"9;
"A"
$PN"1"30;
%"UNIVERSAL_GND"
"1","(-8625,4825)","0","pure_quanta_power","I31";
;
CDS_LIB"pure_quanta_power"
HDL_POWER"GND";
"A"9;
%"VCC_CORE"
"1","(-8775,5650)","0","pure_quanta_power","I32";
;
HDL_POWER"PVDDCR_CPU1_P0_PVCC"
CDS_LIB"pure_quanta_power";
"A"30;
%"ISL99390FRZTR5935"
"1","(-7225,1175)","0","pure_quanta","I33";
;
LOCATION"PU2"
$SEC"1"
CDS_SEC"1"
MATERIAL"IC"
PART_TYPE"SMLF"
VALUE"ISL99390FRZ-TR5935"
CDS_LMAN_SYM_OUTLINE"-300,700,250,-650"
NEEDS_NO_SIZE"TRUE"
CDS_LIB"pure_quanta"
PART_NUMBER"AL099390004";
"PGND2"
$PN"7_9-20_24"31;
"GL2"
$PN"41"51;
"GL1"
$PN"6"50;
"DNC"
$PN"31"47;
"EN"
$PN"35"48;
"PGND3"
$PN"40"31;
"VOS"
$PN"1"52;
"VIN2"
$PN"30"19;
"PGND1"
$PN"5"31;
"SW"
$PN"10_19"62;
"LSET"
$PN"37"39;
"IOUT"
$PN"38"41;
"TOUT_FLT"
$PN"36"44;
"PVCC"
$PN"4"29;
"PHASE"
$PN"32"49;
"VIN1"
$PN"25_29"19;
"BOOT"
$PN"33"24;
"AGND"
$PN"2"31;
"VCC"
$PN"3"48;
"REFIN"
$PN"39"42;
"PWM"
$PN"34"43;
%"UNIVERSAL_GND"
"1","(-6575,450)","0","pure_quanta_power","I34";
;
CDS_LIB"pure_quanta_power"
HDL_POWER"GND";
"A"31;
%"ISL99390FRZTR5935"
"1","(-7200,4125)","0","pure_quanta","I35";
;
LOCATION"PU13"
$SEC"1"
CDS_SEC"1"
MATERIAL"IC"
PART_TYPE"SMLF"
VALUE"ISL99390FRZ-TR5935"
CDS_LMAN_SYM_OUTLINE"-300,700,250,-650"
NEEDS_NO_SIZE"TRUE"
CDS_LIB"pure_quanta"
PART_NUMBER"AL099390004";
"PGND2"
$PN"7_9-20_24"32;
"GL2"
$PN"41"58;
"GL1"
$PN"6"26;
"DNC"
$PN"31"56;
"EN"
$PN"35"57;
"PGND3"
$PN"40"32;
"VOS"
$PN"1"20;
"VIN2"
$PN"30"22;
"PGND1"
$PN"5"32;
"SW"
$PN"10_19"21;
"LSET"
$PN"37"27;
"IOUT"
$PN"38"45;
"TOUT_FLT"
$PN"36"28;
"PVCC"
$PN"4"30;
"PHASE"
$PN"32"15;
"VIN1"
$PN"25_29"22;
"BOOT"
$PN"33"23;
"AGND"
$PN"2"32;
"VCC"
$PN"3"57;
"REFIN"
$PN"39"40;
"PWM"
$PN"34"46;
%"UNIVERSAL_GND"
"1","(-6550,3400)","0","pure_quanta_power","I36";
;
CDS_LIB"pure_quanta_power"
HDL_POWER"GND";
"A"32;
%"Q_CAP"
"1","(-6400,2075)","0","pure_quanta","I37";
;
LOCATION"PC86_2"
$SEC"1"
CDS_SEC"1"
MATERIAL"X7R"
PACK_TYPE"0402"
VOLTAGE"25V"
VALUE"0.1UF"
TOLERANCE"10%"
CDS_LIB"pure_quanta"
PART_NUMBER"CH4104K1B00";
"B"
$PN"2"18;
"A"
$PN"1"19;
%"UNIVERSAL_GND"
"1","(-5875,325)","0","pure_quanta_power","I38";
;
CDS_LIB"pure_quanta_power"
HDL_POWER"GND";
"A"10;
%"Q_RES"
"2","(-5875,550)","0","pure_quanta","I39";
;
LOCATION"PR507"
$SEC"1"
CDS_SEC"1"
PACK_TYPE"0402LF"
VALUE"1.5"
TOLERANCE"1%"
WATTAGE"1/8W"
MATERIAL"EMPTY"
CDS_LIB"pure_quanta"
PART_NUMBER"CS-1504FB00";
"A"
$PN"1"53;
"B"
$PN"2"10;
%"Q_RES"
"2","(-9150,675)","2","pure_quanta","I4";
;
LOCATION"PR77"
$SEC"1"
CDS_SEC"1"
PACK_TYPE"0402LF"
VALUE"8.87K"
TOLERANCE"1%"
MATERIAL"EMPTY"
WATTAGE"1/16W"
CDS_LIB"pure_quanta"
PART_NUMBER"CS28872FB01";
"A"
$PN"1"39;
"B"
$PN"2"8;
%"Q_RES"
"1","(-5975,1525)","0","pure_quanta","I40";
;
LOCATION"PR81"
$SEC"1"
CDS_SEC"1"
PACK_TYPE"0402LF"
WATTAGE"1/16W"
TOLERANCE"1%"
MATERIAL"CHIP"
VALUE"5.6"
CDS_LIB"pure_quanta"
PART_NUMBER"CS-5602FB01";
"B"
$PN"2"25;
"A"
$PN"1"24;
%"Q_CAP"
"1","(-5875,1000)","0","pure_quanta","I41";
;
LOCATION"PC190"
$SEC"1"
CDS_SEC"1"
VOLTAGE"50V"
PACK_TYPE"C0402"
VALUE"560PF"
TOLERANCE"10%"
MATERIAL"EMPTY"
CDS_LIB"pure_quanta"
PART_NUMBER"CH1566K1B09";
"B"
$PN"2"53;
"A"
$PN"1"62;
%"Q_RES"
"1","(-4925,275)","0","pure_quanta","I42";
;
LOCATION"PR83"
$SEC"1"
CDS_SEC"1"
TOLERANCE"5%"
WATTAGE"1/16W"
MATERIAL"CHIP"
VALUE"0"
PACK_TYPE"0402LF"
CDS_LIB"pure_quanta"
PART_NUMBER"CS00002JB13";
"B"
$PN"2"36;
"A"
$PN"1"52;
%"Q_CAP"
"1","(-5175,1400)","0","pure_quanta","I44";
;
LOCATION"PC94"
$SEC"1"
CDS_SEC"1"
VOLTAGE"16V"
TOLERANCE"10%"
PACK_TYPE"0402"
MATERIAL"X7R"
VALUE"0.22UF"
CDS_LIB"pure_quanta"
PART_NUMBER"CH4223K1B00";
"B"
$PN"2"49;
"A"
$PN"1"25;
%"UNIVERSAL_GND"
"1","(-4825,1700)","0","pure_quanta_power","I45";
;
CDS_LIB"pure_quanta_power"
HDL_POWER"GND";
"A"18;
%"Q_INDUCTOR4P_14"
"1","(-4150,1050)","0","pure_quanta","I46";
;
LOCATION"PL11"
$SEC"1"
CDS_SEC"1"
VALUE"150NH"
PART_TYPE"SMLF"
MATERIAL"IND"
CDS_LIB"pure_quanta"
NEEDS_NO_SIZE"TRUE"
PART_NUMBER"CV+15^0TZ04";
"1"
$PN"1"62;
"4"
$PN"4"36;
"3"
$PN"3"60;
"2"
$PN"2"54;
%"Q_CAP"
"1","(-6000,2075)","0","pure_quanta","I47";
;
LOCATION"PC88_2"
$SEC"1"
CDS_SEC"1"
VALUE"1UF"
VOLTAGE"25V"
TOLERANCE"10%"
MATERIAL"X6S"
PACK_TYPE"C0402"
CDS_LIB"pure_quanta"
PART_NUMBER"CH5104KEB02";
"B"
$PN"2"18;
"A"
$PN"1"19;
%"Q_CAP"
"1","(-5600,2075)","0","pure_quanta","I48";
;
LOCATION"PC90_2"
$SEC"1"
CDS_SEC"1"
TOLERANCE"20%"
VOLTAGE"16V"
VALUE"22UF"
MATERIAL"X6S"
PACK_TYPE"C0805"
CDS_LIB"pure_quanta"
PART_NUMBER"CH6223MEA01";
"B"
$PN"2"18;
"A"
$PN"1"19;
%"UNIVERSAL_GND"
"1","(-5875,3275)","0","pure_quanta_power","I49";
;
CDS_LIB"pure_quanta_power"
HDL_POWER"GND";
"A"11;
%"Q_RES"
"2","(-5875,3500)","0","pure_quanta","I50";
;
LOCATION"PR506"
$SEC"1"
CDS_SEC"1"
PACK_TYPE"0402LF"
VALUE"1.5"
TOLERANCE"1%"
WATTAGE"1/8W"
MATERIAL"EMPTY"
CDS_LIB"pure_quanta"
PART_NUMBER"CS-1504FB00";
"A"
$PN"1"55;
"B"
$PN"2"11;
%"Q_CAP"
"1","(-5200,2075)","0","pure_quanta","I51";
;
LOCATION"PC93_2"
$SEC"1"
CDS_SEC"1"
TOLERANCE"20%"
VOLTAGE"16V"
VALUE"22UF"
PACK_TYPE"C0805"
MATERIAL"X6S"
CDS_LIB"pure_quanta"
PART_NUMBER"CH6223MEA01";
"B"
$PN"2"18;
"A"
$PN"1"19;
%"Q_CAP"
"1","(-4825,2075)","0","pure_quanta","I52";
;
LOCATION"PC96_2"
$SEC"1"
CDS_SEC"1"
TOLERANCE"20%"
VOLTAGE"16V"
VALUE"22UF"
MATERIAL"X6S"
PACK_TYPE"C0805"
CDS_LIB"pure_quanta"
PART_NUMBER"CH6223MEA01";
"B"
$PN"2"18;
"A"
$PN"1"19;
%"VCC_CORE"
"1","(-4825,2425)","0","pure_quanta_power","I53";
;
HDL_POWER"SW_P12V_AUX_PVDDCR_CPU1_P0_FLT"
CDS_LIB"pure_quanta_power";
"A"19;
%"Q_RES"
"1","(-4850,3225)","0","pure_quanta","I54";
;
LOCATION"PR84"
$SEC"1"
CDS_SEC"1"
MATERIAL"CHIP"
PACK_TYPE"0402LF"
TOLERANCE"5%"
WATTAGE"1/16W"
VALUE"0"
CDS_LIB"pure_quanta"
PART_NUMBER"CS00002JB13";
"B"
$PN"2"38;
"A"
$PN"1"20;
%"Q_CAP"
"1","(-6425,5025)","0","pure_quanta","I55";
;
LOCATION"PC85_1"
$SEC"1"
CDS_SEC"1"
MATERIAL"X7R"
VALUE"0.1UF"
VOLTAGE"25V"
PACK_TYPE"0402"
TOLERANCE"10%"
CDS_LIB"pure_quanta"
PART_NUMBER"CH4104K1B00";
"B"
$PN"2"17;
"A"
$PN"1"22;
%"Q_RES"
"1","(-5950,4475)","0","pure_quanta","I56";
;
LOCATION"PR82"
$SEC"1"
CDS_SEC"1"
MATERIAL"CHIP"
TOLERANCE"1%"
WATTAGE"1/16W"
VALUE"5.6"
PACK_TYPE"0402LF"
CDS_LIB"pure_quanta"
PART_NUMBER"CS-5602FB01";
"B"
$PN"2"16;
"A"
$PN"1"23;
%"Q_CAP"
"1","(-5875,3950)","0","pure_quanta","I57";
;
LOCATION"PC189"
$SEC"1"
CDS_SEC"1"
PACK_TYPE"C0402"
VOLTAGE"50V"
VALUE"560PF"
TOLERANCE"10%"
MATERIAL"EMPTY"
CDS_LIB"pure_quanta"
PART_NUMBER"CH1566K1B09";
"B"
$PN"2"55;
"A"
$PN"1"21;
%"Q_CAP"
"1","(-6025,5025)","0","pure_quanta","I59";
;
LOCATION"PC87_1"
$SEC"1"
CDS_SEC"1"
PACK_TYPE"C0402"
VALUE"1UF"
VOLTAGE"25V"
MATERIAL"X6S"
TOLERANCE"10%"
CDS_LIB"pure_quanta"
PART_NUMBER"CH5104KEB02";
"B"
$PN"2"17;
"A"
$PN"1"22;
%"Q_CAP"
"1","(-5625,5025)","0","pure_quanta","I60";
;
LOCATION"PC89_1"
$SEC"1"
CDS_SEC"1"
MATERIAL"X6S"
TOLERANCE"20%"
VOLTAGE"16V"
VALUE"22UF"
PACK_TYPE"C0805"
CDS_LIB"pure_quanta"
PART_NUMBER"CH6223MEA01";
"B"
$PN"2"17;
"A"
$PN"1"22;
%"Q_CAP"
"1","(-5225,4350)","0","pure_quanta","I61";
;
LOCATION"PC92"
$SEC"1"
CDS_SEC"1"
PACK_TYPE"0402"
VOLTAGE"16V"
MATERIAL"X7R"
TOLERANCE"10%"
VALUE"0.22UF"
CDS_LIB"pure_quanta"
PART_NUMBER"CH4223K1B00";
"B"
$PN"2"15;
"A"
$PN"1"16;
%"Q_INDUCTOR4P_14"
"1","(-4450,4000)","0","pure_quanta","I62";
;
LOCATION"PL10"
$SEC"1"
CDS_SEC"1"
MATERIAL"IND"
VALUE"150NH"
PART_TYPE"SMLF"
CDS_LIB"pure_quanta"
NEEDS_NO_SIZE"TRUE"
PART_NUMBER"CV+15^0TZ04";
"1"
$PN"1"21;
"4"
$PN"4"38;
"3"
$PN"3"61;
"2"
$PN"2"59;
%"UNIVERSAL_GND"
"1","(-4625,4650)","0","pure_quanta_power","I63";
;
CDS_LIB"pure_quanta_power"
HDL_POWER"GND";
"A"17;
%"Q_CAP"
"1","(-5225,5025)","0","pure_quanta","I64";
;
LOCATION"PC91_1"
$SEC"1"
CDS_SEC"1"
TOLERANCE"20%"
VOLTAGE"16V"
VALUE"22UF"
PACK_TYPE"C0805"
MATERIAL"X6S"
CDS_LIB"pure_quanta"
PART_NUMBER"CH6223MEA01";
"B"
$PN"2"17;
"A"
$PN"1"22;
%"Q_CAP"
"1","(-4850,5025)","0","pure_quanta","I65";
;
LOCATION"PC95_1"
$SEC"1"
CDS_SEC"1"
TOLERANCE"20%"
VOLTAGE"16V"
VALUE"22UF"
MATERIAL"X6S"
PACK_TYPE"C0805"
CDS_LIB"pure_quanta"
PART_NUMBER"CH6223MEA01";
"B"
$PN"2"17;
"A"
$PN"1"22;
%"Q_CAPP"
"1","(-4425,5025)","0","pure_quanta","I66";
;
LOCATION"PC101"
$SEC"1"
CDS_SEC"1"
VOLTAGE"16V"
VALUE"270UF"
MATERIAL"OSCON"
TOLERANCE"20%"
PACK_TYPE"THLF"
CDS_LIB"pure_quanta"
PART_NUMBER"CC72703MD38";
"A"
$PN"1"22;
"B"
$PN"2"17;
%"VCC_CORE"
"1","(-4625,5375)","0","pure_quanta_power","I67";
;
HDL_POWER"SW_P12V_AUX_PVDDCR_CPU1_P0_FLT"
CDS_LIB"pure_quanta_power";
"A"22;
%"Q_CAP"
"1","(-2725,975)","0","pure_quanta","I69";
;
LOCATION"PC106_2"
$SEC"1"
CDS_SEC"1"
PACK_TYPE"C0805"
MATERIAL"X6S"
TOLERANCE"20%"
VALUE"22UF"
VOLTAGE"4V"
CDS_LIB"pure_quanta"
PART_NUMBER"CH622KMEA03";
"B"
$PN"2"35;
"A"
$PN"1"36;
%"Q_CAPP"
"1","(-3700,2675)","0","pure_quanta","I70";
;
LOCATION"PC102"
$SEC"1"
CDS_SEC"1"
PACK_TYPE"SMLF"
TOLERANCE"20%"
MATERIAL"SPCAP"
VALUE"220UF"
VOLTAGE"4V"
CDS_LIB"pure_quanta"
PART_NUMBER"CH122KM8801";
"A"
$PN"1"34;
"B"
$PN"2"33;
%"Q_CAPP"
"1","(-3350,2675)","0","pure_quanta","I71";
;
LOCATION"PC97"
$SEC"1"
CDS_SEC"1"
PACK_TYPE"SMLF"
VALUE"220UF"
VOLTAGE"4V"
TOLERANCE"20%"
MATERIAL"SPCAP"
CDS_LIB"pure_quanta"
PART_NUMBER"CH122KM8801";
"A"
$PN"1"34;
"B"
$PN"2"33;
%"Q_CAPP"
"1","(-3025,2675)","0","pure_quanta","I72";
;
LOCATION"PC98"
$SEC"1"
CDS_SEC"1"
VALUE"220UF"
TOLERANCE"20%"
MATERIAL"SPCAP"
PACK_TYPE"SMLF"
VOLTAGE"4V"
CDS_LIB"pure_quanta"
PART_NUMBER"CH122KM8801";
"A"
$PN"1"34;
"B"
$PN"2"33;
%"Q_CAPP"
"1","(-2700,2675)","0","pure_quanta","I73";
;
LOCATION"PC100"
$SEC"1"
CDS_SEC"1"
MATERIAL"SPCAP"
TOLERANCE"20%"
VALUE"220UF"
VOLTAGE"4V"
PACK_TYPE"SMLF"
CDS_LIB"pure_quanta"
PART_NUMBER"CH122KM8801";
"A"
$PN"1"34;
"B"
$PN"2"33;
%"UNIVERSAL_GND"
"1","(-2400,2300)","0","pure_quanta_power","I74";
;
CDS_LIB"pure_quanta_power"
HDL_POWER"GND";
"A"33;
%"Q_CAPP"
"1","(-2400,2675)","0","pure_quanta","I75";
;
LOCATION"PC103"
$SEC"1"
CDS_SEC"1"
MATERIAL"SPCAP"
TOLERANCE"20%"
VALUE"220UF"
VOLTAGE"4V"
PACK_TYPE"SMLF"
CDS_LIB"pure_quanta"
PART_NUMBER"CH122KM8801";
"A"
$PN"1"34;
"B"
$PN"2"33;
%"VCC_CORE"
"1","(-2400,2975)","0","pure_quanta_power","I76";
;
HDL_POWER"PVDDCR_CPU1_P0"
CDS_LIB"pure_quanta_power";
"A"34;
%"Q_CAP"
"1","(-2300,975)","0","pure_quanta","I77";
;
LOCATION"PC108_2"
$SEC"1"
CDS_SEC"1"
PACK_TYPE"C0805"
MATERIAL"X6S"
TOLERANCE"20%"
VALUE"22UF"
VOLTAGE"4V"
CDS_LIB"pure_quanta"
PART_NUMBER"CH622KMEA03";
"B"
$PN"2"35;
"A"
$PN"1"36;
%"UNIVERSAL_GND"
"1","(-2300,625)","0","pure_quanta_power","I78";
;
CDS_LIB"pure_quanta_power"
HDL_POWER"GND";
"A"35;
%"VCC_CORE"
"1","(-2300,1275)","0","pure_quanta_power","I79";
;
HDL_POWER"PVDDCR_CPU1_P0"
CDS_LIB"pure_quanta_power";
"A"36;
%"UNIVERSAL_GND"
"1","(-1850,3575)","0","pure_quanta_power","I80";
;
CDS_LIB"pure_quanta_power"
HDL_POWER"GND";
"A"37;
%"Q_CAPP"
"1","(-4025,5025)","0","pure_quanta","I82";
;
LOCATION"PC104"
$SEC"1"
CDS_SEC"1"
VOLTAGE"16V"
VALUE"270UF"
PACK_TYPE"THLF"
TOLERANCE"20%"
MATERIAL"OSCON"
CDS_LIB"pure_quanta"
PART_NUMBER"CC72703MD38";
"A"
$PN"1"22;
"B"
$PN"2"17;
%"Q_INDUCTOR"
"1","(-3625,5300)","0","pure_quanta","I83";
;
LOCATION"PL12"
$SEC"1"
CDS_SEC"1"
MATERIAL"IND"
PACK_TYPE"SMLF"
VALUE"50NH/86A"
NEEDS_NO_SIZE"TRUE"
CDS_LIB"pure_quanta"
PART_NUMBER"CVA50^0MZ09";
"1"
$PN"1"22;
"2"
$PN"2"13;
%"Q_CAP"
"1","(-2975,3925)","0","pure_quanta","I84";
;
LOCATION"PC99"
$SEC"1"
CDS_SEC"1"
PACK_TYPE"0402"
VOLTAGE"25V"
VALUE"0.1UF"
TOLERANCE"10%"
MATERIAL"X7R"
CDS_LIB"pure_quanta"
PART_NUMBER"CH4104K1B00";
"B"
$PN"2"37;
"A"
$PN"1"38;
%"UNIVERSAL_GND"
"1","(-3250,4725)","0","pure_quanta_power","I85";
;
CDS_LIB"pure_quanta_power"
HDL_POWER"GND";
"A"12;
%"Q_CAP"
"1","(-2575,3925)","0","pure_quanta","I86";
;
LOCATION"PC102_1"
$SEC"1"
CDS_SEC"1"
PACK_TYPE"C0805"
MATERIAL"X6S"
TOLERANCE"20%"
VALUE"22UF"
VOLTAGE"4V"
CDS_LIB"pure_quanta"
PART_NUMBER"CH622KMEA03";
"B"
$PN"2"37;
"A"
$PN"1"38;
%"Q_CAP"
"1","(-3250,5050)","0","pure_quanta","I87";
;
LOCATION"PC85"
$SEC"1"
CDS_SEC"1"
VALUE"0.1UF"
VOLTAGE"25V"
PACK_TYPE"0402"
MATERIAL"X7R"
TOLERANCE"10%"
CDS_LIB"pure_quanta"
PART_NUMBER"CH4104K1B00";
"B"
$PN"2"12;
"A"
$PN"1"13;
%"VCC_CORE"
"1","(-3250,5375)","0","pure_quanta_power","I88";
;
HDL_POWER"P12V_AUX"
CDS_LIB"pure_quanta_power";
"A"13;
%"Q_CAP"
"1","(-2150,3925)","0","pure_quanta","I89";
;
LOCATION"PC105_1"
$SEC"1"
CDS_SEC"1"
PACK_TYPE"C0805"
TOLERANCE"20%"
VALUE"22UF"
VOLTAGE"4V"
MATERIAL"X6S"
CDS_LIB"pure_quanta"
PART_NUMBER"CH622KMEA03";
"B"
$PN"2"37;
"A"
$PN"1"38;
%"UNIVERSAL_GND"
"1","(-8875,1400)","0","pure_quanta_power","I9";
;
CDS_LIB"pure_quanta_power"
HDL_POWER"GND";
"A"14;
%"Q_RES"
"2","(-1850,3900)","0","pure_quanta","I90";
;
LOCATION"PR444"
$SEC"1"
CDS_SEC"1"
WATTAGE"1/16W"
MATERIAL"CHIP"
TOLERANCE"1%"
VALUE"1K"
PACK_TYPE"0402LF"
CDS_LIB"pure_quanta"
PART_NUMBER"CS21002FB06";
"A"
$PN"1"38;
"B"
$PN"2"37;
%"VCC_CORE"
"1","(-1850,4250)","0","pure_quanta_power","I91";
;
HDL_POWER"PVDDCR_CPU1_P0"
CDS_LIB"pure_quanta_power";
"A"38;
END.
